# SCM (Grand Teton) — schematic netlist excerpt (pin names and nets, part order shuffled) for the footprints in the layout excerpt that follows; sources: Cadence DE-HDL packaged netlist, KiCad conversion of 12092022_DA0F0TMDCD0_F0T_Management_Board_D_brd_V3_OCP.brd

R523  Q_RES  10K 1% CHIP  pkg 0402LF  page 32 : A = P3V3_RGM ; B = JTAG_SCM_TDO
R759  Q_RES  33.2 1% CHIP  pkg 0402LF  page 13 : A = UART_BMC_5_RXD ; B = UART_BMC_5_RXD_R

(kicad_pcb
	(version 20260206)
	(generator "pcbnew")
	(generator_version "10.0")
	(general
		(thickness 1.6)
		(legacy_teardrops no)
	)
	(paper "A4")
	(title_block
		(title "12092022_DA0F0TMDCD0_F0T_Management_Board_D_brd_V3_OCP.brd")
		(comment 1 "Grand Teton / footprints 1341-1342 of 1440")
	)
	(layers
		(0 "F.Cu" signal "TOP")
		(4 "In1.Cu" signal "GND")
		(6 "In2.Cu" signal "IN1")
		(8 "In3.Cu" signal "GND1")
		(10 "In4.Cu" signal "IN2")
		(12 "In5.Cu" signal "VCC")
		(14 "In6.Cu" signal "VCC1")
		(16 "In7.Cu" signal "IN3")
		(18 "In8.Cu" signal "GND2")
		(20 "In9.Cu" signal "IN4")
		(22 "In10.Cu" signal "GND3")
		(2 "B.Cu" signal "BOTTOM")
		(9 "F.Adhes" user "F.Adhesive")
		(11 "B.Adhes" user "B.Adhesive")
		(13 "F.Paste" user "Package Geometry/Pastemask Top")
		(15 "B.Paste" user "Package Geometry/Pastemask Bottom")
		(5 "F.SilkS" user "Ref Des/Silkscreen Top")
		(7 "B.SilkS" user "Ref Des/Silkscreen Bottom")
		(1 "F.Mask" user "Board Geometry/Soldermask Top")
		(3 "B.Mask" user "Board Geometry/Soldermask Bottom")
		(17 "Dwgs.User" user "User.Drawings")
		(19 "Cmts.User" user "User.Comments")
		(21 "Eco1.User" user "User.Eco1")
		(23 "Eco2.User" user "User.Eco2")
		(25 "Edge.Cuts" user "Board Geometry/Outline")
		(27 "Margin" user)
		(31 "F.CrtYd" user "Package Geometry/Place Bound Top")
		(29 "B.CrtYd" user "Package Geometry/Place Bound Bottom")
		(35 "F.Fab" user "Ref Des/Assembly Top")
		(33 "B.Fab" user "Ref Des/Assembly Bottom")
	)
	(footprint ""
		(layer "B.Cu")
		(at 65.108582 -30.867604 -90)
		(property "Reference" "R523"
			(at 0 0 90)
			(layer "B.SilkS")
			(hide yes)
			(effects
				(font
					(size 1.27 1.27)
				)
				(justify mirror)
			)
		)
		(property "Value" ""
			(at 0 0 90)
			(layer "B.Fab")
			(effects
				(font
					(size 1.27 1.27)
				)
				(justify mirror)
			)
		)
		(duplicate_pad_numbers_are_jumpers no)
		(fp_line
			(start -0.7874 0.4064)
			(end 0.7874 0.4064)
			(stroke
				(width 0.1524)
				(type default)
			)
			(layer "B.SilkS")
		)
		(fp_line
			(start 0.7874 0.4064)
			(end 0.7874 -0.4064)
			(stroke
				(width 0.1524)
				(type default)
			)
			(layer "B.SilkS")
		)
		(fp_line
			(start -0.7874 -0.4064)
			(end -0.7874 0.4064)
			(stroke
				(width 0.1524)
				(type default)
			)
			(layer "B.SilkS")
		)
		(fp_line
			(start 0.7874 -0.4064)
			(end -0.7874 -0.4064)
			(stroke
				(width 0.1524)
				(type default)
			)
			(layer "B.SilkS")
		)
		(fp_line
			(start -0.67945 0.3048)
			(end -0.120396 0.3048)
			(stroke
				(width 0.1)
				(type default)
			)
			(layer "B.Fab")
		)
		(fp_line
			(start -0.120396 0.3048)
			(end -0.120396 0.2794)
			(stroke
				(width 0.1)
				(type default)
			)
			(layer "B.Fab")
		)
		(fp_line
			(start 0.12065 0.3048)
			(end 0.67945 0.3048)
			(stroke
				(width 0.1)
				(type default)
			)
			(layer "B.Fab")
		)
		(fp_line
			(start 0.67945 0.3048)
			(end 0.67945 -0.305054)
			(stroke
				(width 0.1)
				(type default)
			)
			(layer "B.Fab")
		)
		(fp_line
			(start -0.120396 0.2794)
			(end 0.12065 0.2794)
			(stroke
				(width 0.1)
				(type default)
			)
			(layer "B.Fab")
		)
		(fp_line
			(start 0.12065 0.2794)
			(end 0.12065 0.3048)
			(stroke
				(width 0.1)
				(type default)
			)
			(layer "B.Fab")
		)
		(fp_line
			(start -0.12065 -0.2794)
			(end -0.12065 -0.3048)
			(stroke
				(width 0.1)
				(type default)
			)
			(layer "B.Fab")
		)
		(fp_line
			(start 0.12065 -0.2794)
			(end -0.12065 -0.2794)
			(stroke
				(width 0.1)
				(type default)
			)
			(layer "B.Fab")
		)
		(fp_line
			(start -0.67945 -0.3048)
			(end -0.67945 0.3048)
			(stroke
				(width 0.1)
				(type default)
			)
			(layer "B.Fab")
		)
		(fp_line
			(start -0.12065 -0.3048)
			(end -0.67945 -0.3048)
			(stroke
				(width 0.1)
				(type default)
			)
			(layer "B.Fab")
		)
		(fp_line
			(start 0.12065 -0.305054)
			(end 0.12065 -0.2794)
			(stroke
				(width 0.1)
				(type default)
			)
			(layer "B.Fab")
		)
		(fp_line
			(start 0.67945 -0.305054)
			(end 0.12065 -0.305054)
			(stroke
				(width 0.1)
				(type default)
			)
			(layer "B.Fab")
		)
		(pad "1" smd circle
			(at 0.40005 0 90)
			(size 0 0)
			(layers "B.Cu" "B.Mask" "B.Paste")
			(net "P3V3_RGM")
		)
		(pad "2" smd circle
			(at -0.40005 0 90)
			(size 0 0)
			(layers "B.Cu" "B.Mask" "B.Paste")
			(net "JTAG_SCM_TDO")
		)
	)
	(footprint ""
		(layer "B.Cu")
		(at 66.0908 -34.63798 90)
		(property "Reference" "R759"
			(at 0 0 90)
			(layer "B.SilkS")
			(hide yes)
			(effects
				(font
					(size 1.27 1.27)
				)
				(justify mirror)
			)
		)
		(property "Value" ""
			(at 0 0 90)
			(layer "B.Fab")
			(effects
				(font
					(size 1.27 1.27)
				)
				(justify mirror)
			)
		)
		(duplicate_pad_numbers_are_jumpers no)
		(fp_line
			(start 0.7874 -0.4064)
			(end -0.7874 -0.4064)
			(stroke
				(width 0.1524)
				(type default)
			)
			(layer "B.SilkS")
		)
		(fp_line
			(start -0.7874 -0.4064)
			(end -0.7874 0.4064)
			(stroke
				(width 0.1524)
				(type default)
			)
			(layer "B.SilkS")
		)
		(fp_line
			(start 0.7874 0.4064)
			(end 0.7874 -0.4064)
			(stroke
				(width 0.1524)
				(type default)
			)
			(layer "B.SilkS")
		)
		(fp_line
			(start -0.7874 0.4064)
			(end 0.7874 0.4064)
			(stroke
				(width 0.1524)
				(type default)
			)
			(layer "B.SilkS")
		)
		(fp_line
			(start 0.67945 -0.305054)
			(end 0.12065 -0.305054)
			(stroke
				(width 0.1)
				(type default)
			)
			(layer "B.Fab")
		)
		(fp_line
			(start 0.12065 -0.305054)
			(end 0.12065 -0.2794)
			(stroke
				(width 0.1)
				(type default)
			)
			(layer "B.Fab")
		)
		(fp_line
			(start -0.12065 -0.3048)
			(end -0.67945 -0.3048)
			(stroke
				(width 0.1)
				(type default)
			)
			(layer "B.Fab")
		)
		(fp_line
			(start -0.67945 -0.3048)
			(end -0.67945 0.3048)
			(stroke
				(width 0.1)
				(type default)
			)
			(layer "B.Fab")
		)
		(fp_line
			(start 0.12065 -0.2794)
			(end -0.12065 -0.2794)
			(stroke
				(width 0.1)
				(type default)
			)
			(layer "B.Fab")
		)
		(fp_line
			(start -0.12065 -0.2794)
			(end -0.12065 -0.3048)
			(stroke
				(width 0.1)
				(type default)
			)
			(layer "B.Fab")
		)
		(fp_line
			(start 0.12065 0.2794)
			(end 0.12065 0.3048)
			(stroke
				(width 0.1)
				(type default)
			)
			(layer "B.Fab")
		)
		(fp_line
			(start -0.120396 0.2794)
			(end 0.12065 0.2794)
			(stroke
				(width 0.1)
				(type default)
			)
			(layer "B.Fab")
		)
		(fp_line
			(start 0.67945 0.3048)
			(end 0.67945 -0.305054)
			(stroke
				(width 0.1)
				(type default)
			)
			(layer "B.Fab")
		)
		(fp_line
			(start 0.12065 0.3048)
			(end 0.67945 0.3048)
			(stroke
				(width 0.1)
				(type default)
			)
			(layer "B.Fab")
		)
		(fp_line
			(start -0.120396 0.3048)
			(end -0.120396 0.2794)
			(stroke
				(width 0.1)
				(type default)
			)
			(layer "B.Fab")
		)
		(fp_line
			(start -0.67945 0.3048)
			(end -0.120396 0.3048)
			(stroke
				(width 0.1)
				(type default)
			)
			(layer "B.Fab")
		)
		(pad "1" smd circle
			(at 0.40005 0 270)
			(size 0 0)
			(layers "B.Cu" "B.Mask" "B.Paste")
			(net "UART_BMC_5_RXD")
		)
		(pad "2" smd circle
			(at -0.40005 0 270)
			(size 0 0)
			(layers "B.Cu" "B.Mask" "B.Paste")
			(net "UART_BMC_5_RXD_R")
		)
	)
)
